(kicad_pcb
	(version 20260206)
	(generator "pcbnew")
	(generator_version "10.0")
	(general
		(thickness 1.6)
		(legacy_teardrops no)
	)
	(paper "A4")
	(title_block
		(title "12092022_DA0F0TMDCD0_F0T_Management_Board_D_brd_V3_OCP.brd")
		(comment 1 "Grand Teton / footprints 275-280 of 1440")
	)
	(layers
		(0 "F.Cu" signal "TOP")
		(4 "In1.Cu" signal "GND")
		(6 "In2.Cu" signal "IN1")
		(8 "In3.Cu" signal "GND1")
		(10 "In4.Cu" signal "IN2")
		(12 "In5.Cu" signal "VCC")
		(14 "In6.Cu" signal "VCC1")
		(16 "In7.Cu" signal "IN3")
		(18 "In8.Cu" signal "GND2")
		(20 "In9.Cu" signal "IN4")
		(22 "In10.Cu" signal "GND3")
		(2 "B.Cu" signal "BOTTOM")
		(9 "F.Adhes" user "F.Adhesive")
		(11 "B.Adhes" user "B.Adhesive")
		(13 "F.Paste" user "Package Geometry/Pastemask Top")
		(15 "B.Paste" user "Package Geometry/Pastemask Bottom")
		(5 "F.SilkS" user "Ref Des/Silkscreen Top")
		(7 "B.SilkS" user "Ref Des/Silkscreen Bottom")
		(1 "F.Mask" user "Board Geometry/Soldermask Top")
		(3 "B.Mask" user "Board Geometry/Soldermask Bottom")
		(17 "Dwgs.User" user "User.Drawings")
		(19 "Cmts.User" user "User.Comments")
		(21 "Eco1.User" user "User.Eco1")
		(23 "Eco2.User" user "User.Eco2")
		(25 "Edge.Cuts" user "Board Geometry/Outline")
		(27 "Margin" user)
		(31 "F.CrtYd" user "Package Geometry/Place Bound Top")
		(29 "B.CrtYd" user "Package Geometry/Place Bound Bottom")
		(35 "F.Fab" user "Ref Des/Assembly Top")
		(33 "B.Fab" user "Ref Des/Assembly Bottom")
	)
	(footprint ""
		(layer "F.Cu")
		(at 10.033 -89.408)
		(property "Reference" "C223"
			(at 0 0 0)
			(layer "F.SilkS")
			(hide yes)
			(effects
				(font
					(size 1.27 1.27)
				)
			)
		)
		(property "Value" ""
			(at 0 0 0)
			(layer "F.Fab")
			(effects
				(font
					(size 1.27 1.27)
				)
			)
		)
		(duplicate_pad_numbers_are_jumpers no)
		(fp_line
			(start -0.7874 -0.4064)
			(end 0.7874 -0.4064)
			(stroke
				(width 0.1524)
				(type default)
			)
			(layer "F.SilkS")
		)
		(fp_line
			(start -0.7874 0.4064)
			(end -0.7874 -0.4064)
			(stroke
				(width 0.1524)
				(type default)
			)
			(layer "F.SilkS")
		)
		(fp_line
			(start 0.7874 -0.4064)
			(end 0.7874 0.4064)
			(stroke
				(width 0.1524)
				(type default)
			)
			(layer "F.SilkS")
		)
		(fp_line
			(start 0.7874 0.4064)
			(end -0.7874 0.4064)
			(stroke
				(width 0.1524)
				(type default)
			)
			(layer "F.SilkS")
		)
		(fp_line
			(start -0.67945 -0.305054)
			(end -0.12065 -0.305054)
			(stroke
				(width 0.1)
				(type default)
			)
			(layer "F.Fab")
		)
		(fp_line
			(start -0.67945 0.3048)
			(end -0.67945 -0.305054)
			(stroke
				(width 0.1)
				(type default)
			)
			(layer "F.Fab")
		)
		(fp_line
			(start -0.12065 -0.305054)
			(end -0.12065 -0.2794)
			(stroke
				(width 0.1)
				(type default)
			)
			(layer "F.Fab")
		)
		(fp_line
			(start -0.12065 -0.2794)
			(end 0.12065 -0.2794)
			(stroke
				(width 0.1)
				(type default)
			)
			(layer "F.Fab")
		)
		(fp_line
			(start -0.12065 0.2794)
			(end -0.12065 0.3048)
			(stroke
				(width 0.1)
				(type default)
			)
			(layer "F.Fab")
		)
		(fp_line
			(start -0.12065 0.3048)
			(end -0.67945 0.3048)
			(stroke
				(width 0.1)
				(type default)
			)
			(layer "F.Fab")
		)
		(fp_line
			(start 0.120396 0.2794)
			(end -0.12065 0.2794)
			(stroke
				(width 0.1)
				(type default)
			)
			(layer "F.Fab")
		)
		(fp_line
			(start 0.120396 0.3048)
			(end 0.120396 0.2794)
			(stroke
				(width 0.1)
				(type default)
			)
			(layer "F.Fab")
		)
		(fp_line
			(start 0.12065 -0.3048)
			(end 0.67945 -0.3048)
			(stroke
				(width 0.1)
				(type default)
			)
			(layer "F.Fab")
		)
		(fp_line
			(start 0.12065 -0.2794)
			(end 0.12065 -0.3048)
			(stroke
				(width 0.1)
				(type default)
			)
			(layer "F.Fab")
		)
		(fp_line
			(start 0.67945 -0.3048)
			(end 0.67945 0.3048)
			(stroke
				(width 0.1)
				(type default)
			)
			(layer "F.Fab")
		)
		(fp_line
			(start 0.67945 0.3048)
			(end 0.120396 0.3048)
			(stroke
				(width 0.1)
				(type default)
			)
			(layer "F.Fab")
		)
		(pad "1" smd circle
			(at -0.40005 0)
			(size 0 0)
			(layers "F.Cu" "F.Mask" "F.Paste")
			(net "RST_BMC_SRST_BUF_R_N")
		)
		(pad "2" smd circle
			(at 0.40005 0)
			(size 0 0)
			(layers "F.Cu" "F.Mask" "F.Paste")
			(net "GND")
		)
	)
	(footprint ""
		(layer "F.Cu")
		(at 29.1592 -65.8622 90)
		(property "Reference" "C268"
			(at 0 0 90)
			(layer "F.SilkS")
			(hide yes)
			(effects
				(font
					(size 1.27 1.27)
				)
			)
		)
		(property "Value" ""
			(at 0 0 90)
			(layer "F.Fab")
			(effects
				(font
					(size 1.27 1.27)
				)
			)
		)
		(duplicate_pad_numbers_are_jumpers no)
		(fp_line
			(start 0.7874 -0.4064)
			(end 0.7874 0.4064)
			(stroke
				(width 0.1524)
				(type default)
			)
			(layer "F.SilkS")
		)
		(fp_line
			(start -0.7874 -0.4064)
			(end 0.7874 -0.4064)
			(stroke
				(width 0.1524)
				(type default)
			)
			(layer "F.SilkS")
		)
		(fp_line
			(start 0.7874 0.4064)
			(end -0.7874 0.4064)
			(stroke
				(width 0.1524)
				(type default)
			)
			(layer "F.SilkS")
		)
		(fp_line
			(start -0.7874 0.4064)
			(end -0.7874 -0.4064)
			(stroke
				(width 0.1524)
				(type default)
			)
			(layer "F.SilkS")
		)
		(fp_line
			(start -0.12065 -0.305054)
			(end -0.12065 -0.2794)
			(stroke
				(width 0.1)
				(type default)
			)
			(layer "F.Fab")
		)
		(fp_line
			(start -0.67945 -0.305054)
			(end -0.12065 -0.305054)
			(stroke
				(width 0.1)
				(type default)
			)
			(layer "F.Fab")
		)
		(fp_line
			(start 0.67945 -0.3048)
			(end 0.67945 0.3048)
			(stroke
				(width 0.1)
				(type default)
			)
			(layer "F.Fab")
		)
		(fp_line
			(start 0.12065 -0.3048)
			(end 0.67945 -0.3048)
			(stroke
				(width 0.1)
				(type default)
			)
			(layer "F.Fab")
		)
		(fp_line
			(start 0.12065 -0.2794)
			(end 0.12065 -0.3048)
			(stroke
				(width 0.1)
				(type default)
			)
			(layer "F.Fab")
		)
		(fp_line
			(start -0.12065 -0.2794)
			(end 0.12065 -0.2794)
			(stroke
				(width 0.1)
				(type default)
			)
			(layer "F.Fab")
		)
		(fp_line
			(start 0.120396 0.2794)
			(end -0.12065 0.2794)
			(stroke
				(width 0.1)
				(type default)
			)
			(layer "F.Fab")
		)
		(fp_line
			(start -0.12065 0.2794)
			(end -0.12065 0.3048)
			(stroke
				(width 0.1)
				(type default)
			)
			(layer "F.Fab")
		)
		(fp_line
			(start 0.67945 0.3048)
			(end 0.120396 0.3048)
			(stroke
				(width 0.1)
				(type default)
			)
			(layer "F.Fab")
		)
		(fp_line
			(start 0.120396 0.3048)
			(end 0.120396 0.2794)
			(stroke
				(width 0.1)
				(type default)
			)
			(layer "F.Fab")
		)
		(fp_line
			(start -0.12065 0.3048)
			(end -0.67945 0.3048)
			(stroke
				(width 0.1)
				(type default)
			)
			(layer "F.Fab")
		)
		(fp_line
			(start -0.67945 0.3048)
			(end -0.67945 -0.305054)
			(stroke
				(width 0.1)
				(type default)
			)
			(layer "F.Fab")
		)
		(pad "1" smd circle
			(at -0.40005 0 90)
			(size 0 0)
			(layers "F.Cu" "F.Mask" "F.Paste")
			(net "P3V3_AUX")
		)
		(pad "2" smd circle
			(at 0.40005 0 90)
			(size 0 0)
			(layers "F.Cu" "F.Mask" "F.Paste")
			(net "GND")
		)
	)
	(footprint ""
		(layer "F.Cu")
		(at 51.816 -30.861 90)
		(property "Reference" "R692"
			(at 0 0 90)
			(layer "F.SilkS")
			(hide yes)
			(effects
				(font
					(size 1.27 1.27)
				)
			)
		)
		(property "Value" ""
			(at 0 0 90)
			(layer "F.Fab")
			(effects
				(font
					(size 1.27 1.27)
				)
			)
		)
		(duplicate_pad_numbers_are_jumpers no)
		(fp_line
			(start 0.7874 -0.4064)
			(end 0.7874 0.4064)
			(stroke
				(width 0.1524)
				(type default)
			)
			(layer "F.SilkS")
		)
		(fp_line
			(start -0.7874 -0.4064)
			(end 0.7874 -0.4064)
			(stroke
				(width 0.1524)
				(type default)
			)
			(layer "F.SilkS")
		)
		(fp_line
			(start 0.7874 0.4064)
			(end -0.7874 0.4064)
			(stroke
				(width 0.1524)
				(type default)
			)
			(layer "F.SilkS")
		)
		(fp_line
			(start -0.7874 0.4064)
			(end -0.7874 -0.4064)
			(stroke
				(width 0.1524)
				(type default)
			)
			(layer "F.SilkS")
		)
		(fp_line
			(start -0.12065 -0.305054)
			(end -0.12065 -0.2794)
			(stroke
				(width 0.1)
				(type default)
			)
			(layer "F.Fab")
		)
		(fp_line
			(start -0.67945 -0.305054)
			(end -0.12065 -0.305054)
			(stroke
				(width 0.1)
				(type default)
			)
			(layer "F.Fab")
		)
		(fp_line
			(start 0.67945 -0.3048)
			(end 0.67945 0.3048)
			(stroke
				(width 0.1)
				(type default)
			)
			(layer "F.Fab")
		)
		(fp_line
			(start 0.12065 -0.3048)
			(end 0.67945 -0.3048)
			(stroke
				(width 0.1)
				(type default)
			)
			(layer "F.Fab")
		)
		(fp_line
			(start 0.12065 -0.2794)
			(end 0.12065 -0.3048)
			(stroke
				(width 0.1)
				(type default)
			)
			(layer "F.Fab")
		)
		(fp_line
			(start -0.12065 -0.2794)
			(end 0.12065 -0.2794)
			(stroke
				(width 0.1)
				(type default)
			)
			(layer "F.Fab")
		)
		(fp_line
			(start 0.120396 0.2794)
			(end -0.12065 0.2794)
			(stroke
				(width 0.1)
				(type default)
			)
			(layer "F.Fab")
		)
		(fp_line
			(start -0.12065 0.2794)
			(end -0.12065 0.3048)
			(stroke
				(width 0.1)
				(type default)
			)
			(layer "F.Fab")
		)
		(fp_line
			(start 0.67945 0.3048)
			(end 0.120396 0.3048)
			(stroke
				(width 0.1)
				(type default)
			)
			(layer "F.Fab")
		)
		(fp_line
			(start 0.120396 0.3048)
			(end 0.120396 0.2794)
			(stroke
				(width 0.1)
				(type default)
			)
			(layer "F.Fab")
		)
		(fp_line
			(start -0.12065 0.3048)
			(end -0.67945 0.3048)
			(stroke
				(width 0.1)
				(type default)
			)
			(layer "F.Fab")
		)
		(fp_line
			(start -0.67945 0.3048)
			(end -0.67945 -0.305054)
			(stroke
				(width 0.1)
				(type default)
			)
			(layer "F.Fab")
		)
		(pad "1" smd circle
			(at -0.40005 0 90)
			(size 0 0)
			(layers "F.Cu" "F.Mask" "F.Paste")
			(net "P3V3_AUX")
		)
		(pad "2" smd circle
			(at 0.40005 0 90)
			(size 0 0)
			(layers "F.Cu" "F.Mask" "F.Paste")
			(net "SMB_BMC_MM15_SDA")
		)
	)
	(footprint ""
		(layer "F.Cu")
		(at 45.259244 -30.791404 90)
		(property "Reference" "R244"
			(at 0 0 90)
			(layer "F.SilkS")
			(hide yes)
			(effects
				(font
					(size 1.27 1.27)
				)
			)
		)
		(property "Value" ""
			(at 0 0 90)
			(layer "F.Fab")
			(effects
				(font
					(size 1.27 1.27)
				)
			)
		)
		(duplicate_pad_numbers_are_jumpers no)
		(fp_line
			(start 0.7874 -0.4064)
			(end 0.7874 0.4064)
			(stroke
				(width 0.1524)
				(type default)
			)
			(layer "F.SilkS")
		)
		(fp_line
			(start -0.7874 -0.4064)
			(end 0.7874 -0.4064)
			(stroke
				(width 0.1524)
				(type default)
			)
			(layer "F.SilkS")
		)
		(fp_line
			(start 0.7874 0.4064)
			(end -0.7874 0.4064)
			(stroke
				(width 0.1524)
				(type default)
			)
			(layer "F.SilkS")
		)
		(fp_line
			(start -0.7874 0.4064)
			(end -0.7874 -0.4064)
			(stroke
				(width 0.1524)
				(type default)
			)
			(layer "F.SilkS")
		)
		(fp_line
			(start -0.12065 -0.305054)
			(end -0.12065 -0.2794)
			(stroke
				(width 0.1)
				(type default)
			)
			(layer "F.Fab")
		)
		(fp_line
			(start -0.67945 -0.305054)
			(end -0.12065 -0.305054)
			(stroke
				(width 0.1)
				(type default)
			)
			(layer "F.Fab")
		)
		(fp_line
			(start 0.67945 -0.3048)
			(end 0.67945 0.3048)
			(stroke
				(width 0.1)
				(type default)
			)
			(layer "F.Fab")
		)
		(fp_line
			(start 0.12065 -0.3048)
			(end 0.67945 -0.3048)
			(stroke
				(width 0.1)
				(type default)
			)
			(layer "F.Fab")
		)
		(fp_line
			(start 0.12065 -0.2794)
			(end 0.12065 -0.3048)
			(stroke
				(width 0.1)
				(type default)
			)
			(layer "F.Fab")
		)
		(fp_line
			(start -0.12065 -0.2794)
			(end 0.12065 -0.2794)
			(stroke
				(width 0.1)
				(type default)
			)
			(layer "F.Fab")
		)
		(fp_line
			(start 0.120396 0.2794)
			(end -0.12065 0.2794)
			(stroke
				(width 0.1)
				(type default)
			)
			(layer "F.Fab")
		)
		(fp_line
			(start -0.12065 0.2794)
			(end -0.12065 0.3048)
			(stroke
				(width 0.1)
				(type default)
			)
			(layer "F.Fab")
		)
		(fp_line
			(start 0.67945 0.3048)
			(end 0.120396 0.3048)
			(stroke
				(width 0.1)
				(type default)
			)
			(layer "F.Fab")
		)
		(fp_line
			(start 0.120396 0.3048)
			(end 0.120396 0.2794)
			(stroke
				(width 0.1)
				(type default)
			)
			(layer "F.Fab")
		)
		(fp_line
			(start -0.12065 0.3048)
			(end -0.67945 0.3048)
			(stroke
				(width 0.1)
				(type default)
			)
			(layer "F.Fab")
		)
		(fp_line
			(start -0.67945 0.3048)
			(end -0.67945 -0.305054)
			(stroke
				(width 0.1)
				(type default)
			)
			(layer "F.Fab")
		)
		(pad "1" smd circle
			(at -0.40005 0 90)
			(size 0 0)
			(layers "F.Cu" "F.Mask" "F.Paste")
			(net "P3V3_AUX")
		)
		(pad "2" smd circle
			(at 0.40005 0 90)
			(size 0 0)
			(layers "F.Cu" "F.Mask" "F.Paste")
			(net "SMB_BMC_MM1_SCL")
		)
	)
	(footprint ""
		(layer "F.Cu")
		(at 23.47087 -33.904174 -90)
		(property "Reference" "PR500"
			(at 0 0 270)
			(layer "F.SilkS")
			(hide yes)
			(effects
				(font
					(size 1.27 1.27)
				)
			)
		)
		(property "Value" ""
			(at 0 0 270)
			(layer "F.Fab")
			(effects
				(font
					(size 1.27 1.27)
				)
			)
		)
		(duplicate_pad_numbers_are_jumpers no)
		(fp_line
			(start -0.7874 0.4064)
			(end -0.7874 -0.4064)
			(stroke
				(width 0.1524)
				(type default)
			)
			(layer "F.SilkS")
		)
		(fp_line
			(start 0.7874 0.4064)
			(end -0.7874 0.4064)
			(stroke
				(width 0.1524)
				(type default)
			)
			(layer "F.SilkS")
		)
		(fp_line
			(start -0.7874 -0.4064)
			(end 0.7874 -0.4064)
			(stroke
				(width 0.1524)
				(type default)
			)
			(layer "F.SilkS")
		)
		(fp_line
			(start 0.7874 -0.4064)
			(end 0.7874 0.4064)
			(stroke
				(width 0.1524)
				(type default)
			)
			(layer "F.SilkS")
		)
		(fp_line
			(start -0.67945 0.3048)
			(end -0.67945 -0.305054)
			(stroke
				(width 0.1)
				(type default)
			)
			(layer "F.Fab")
		)
		(fp_line
			(start -0.12065 0.3048)
			(end -0.67945 0.3048)
			(stroke
				(width 0.1)
				(type default)
			)
			(layer "F.Fab")
		)
		(fp_line
			(start 0.120396 0.3048)
			(end 0.120396 0.2794)
			(stroke
				(width 0.1)
				(type default)
			)
			(layer "F.Fab")
		)
		(fp_line
			(start 0.67945 0.3048)
			(end 0.120396 0.3048)
			(stroke
				(width 0.1)
				(type default)
			)
			(layer "F.Fab")
		)
		(fp_line
			(start -0.12065 0.2794)
			(end -0.12065 0.3048)
			(stroke
				(width 0.1)
				(type default)
			)
			(layer "F.Fab")
		)
		(fp_line
			(start 0.120396 0.2794)
			(end -0.12065 0.2794)
			(stroke
				(width 0.1)
				(type default)
			)
			(layer "F.Fab")
		)
		(fp_line
			(start -0.12065 -0.2794)
			(end 0.12065 -0.2794)
			(stroke
				(width 0.1)
				(type default)
			)
			(layer "F.Fab")
		)
		(fp_line
			(start 0.12065 -0.2794)
			(end 0.12065 -0.3048)
			(stroke
				(width 0.1)
				(type default)
			)
			(layer "F.Fab")
		)
		(fp_line
			(start 0.12065 -0.3048)
			(end 0.67945 -0.3048)
			(stroke
				(width 0.1)
				(type default)
			)
			(layer "F.Fab")
		)
		(fp_line
			(start 0.67945 -0.3048)
			(end 0.67945 0.3048)
			(stroke
				(width 0.1)
				(type default)
			)
			(layer "F.Fab")
		)
		(fp_line
			(start -0.67945 -0.305054)
			(end -0.12065 -0.305054)
			(stroke
				(width 0.1)
				(type default)
			)
			(layer "F.Fab")
		)
		(fp_line
			(start -0.12065 -0.305054)
			(end -0.12065 -0.2794)
			(stroke
				(width 0.1)
				(type default)
			)
			(layer "F.Fab")
		)
		(pad "1" smd circle
			(at -0.40005 0 270)
			(size 0 0)
			(layers "F.Cu" "F.Mask" "F.Paste")
			(net "P3V3_AUX")
		)
		(pad "2" smd circle
			(at 0.40005 0 270)
			(size 0 0)
			(layers "F.Cu" "F.Mask" "F.Paste")
			(net "PWRGD_P1V0_AUX_R")
		)
	)
	(footprint ""
		(layer "F.Cu")
		(at 4.218432 -47.989744 90)
		(property "Reference" "PC208"
			(at 0 0 90)
			(layer "F.SilkS")
			(hide yes)
			(effects
				(font
					(size 1.27 1.27)
				)
			)
		)
		(property "Value" ""
			(at 0 0 90)
			(layer "F.Fab")
			(effects
				(font
					(size 1.27 1.27)
				)
			)
		)
		(duplicate_pad_numbers_are_jumpers no)
		(fp_line
			(start 0.7874 -0.4064)
			(end 0.7874 0.4064)
			(stroke
				(width 0.1524)
				(type default)
			)
			(layer "F.SilkS")
		)
		(fp_line
			(start -0.7874 -0.4064)
			(end 0.7874 -0.4064)
			(stroke
				(width 0.1524)
				(type default)
			)
			(layer "F.SilkS")
		)
		(fp_line
			(start 0.7874 0.4064)
			(end -0.7874 0.4064)
			(stroke
				(width 0.1524)
				(type default)
			)
			(layer "F.SilkS")
		)
		(fp_line
			(start -0.7874 0.4064)
			(end -0.7874 -0.4064)
			(stroke
				(width 0.1524)
				(type default)
			)
			(layer "F.SilkS")
		)
		(fp_line
			(start -0.12065 -0.305054)
			(end -0.12065 -0.2794)
			(stroke
				(width 0.1)
				(type default)
			)
			(layer "F.Fab")
		)
		(fp_line
			(start -0.67945 -0.305054)
			(end -0.12065 -0.305054)
			(stroke
				(width 0.1)
				(type default)
			)
			(layer "F.Fab")
		)
		(fp_line
			(start 0.67945 -0.3048)
			(end 0.67945 0.3048)
			(stroke
				(width 0.1)
				(type default)
			)
			(layer "F.Fab")
		)
		(fp_line
			(start 0.12065 -0.3048)
			(end 0.67945 -0.3048)
			(stroke
				(width 0.1)
				(type default)
			)
			(layer "F.Fab")
		)
		(fp_line
			(start 0.12065 -0.2794)
			(end 0.12065 -0.3048)
			(stroke
				(width 0.1)
				(type default)
			)
			(layer "F.Fab")
		)
		(fp_line
			(start -0.12065 -0.2794)
			(end 0.12065 -0.2794)
			(stroke
				(width 0.1)
				(type default)
			)
			(layer "F.Fab")
		)
		(fp_line
			(start 0.120396 0.2794)
			(end -0.12065 0.2794)
			(stroke
				(width 0.1)
				(type default)
			)
			(layer "F.Fab")
		)
		(fp_line
			(start -0.12065 0.2794)
			(end -0.12065 0.3048)
			(stroke
				(width 0.1)
				(type default)
			)
			(layer "F.Fab")
		)
		(fp_line
			(start 0.67945 0.3048)
			(end 0.120396 0.3048)
			(stroke
				(width 0.1)
				(type default)
			)
			(layer "F.Fab")
		)
		(fp_line
			(start 0.120396 0.3048)
			(end 0.120396 0.2794)
			(stroke
				(width 0.1)
				(type default)
			)
			(layer "F.Fab")
		)
		(fp_line
			(start -0.12065 0.3048)
			(end -0.67945 0.3048)
			(stroke
				(width 0.1)
				(type default)
			)
			(layer "F.Fab")
		)
		(fp_line
			(start -0.67945 0.3048)
			(end -0.67945 -0.305054)
			(stroke
				(width 0.1)
				(type default)
			)
			(layer "F.Fab")
		)
		(pad "1" smd circle
			(at -0.40005 0 90)
			(size 0 0)
			(layers "F.Cu" "F.Mask" "F.Paste")
			(net "P5V_AUX_VCC")
		)
		(pad "2" smd circle
			(at 0.40005 0 90)
			(size 0 0)
			(layers "F.Cu" "F.Mask" "F.Paste")
			(net "GND")
		)
	)
)
